(kicad_pcb
	(version 20260206)
	(generator "pcbnew")
	(generator_version "10.0")
	(general
		(thickness 1.6)
		(legacy_teardrops no)
	)
	(paper "A4")
	(title_block
		(title "Bryce Canyon_F.DPB_16315-1-OCP.brd")
		(comment 1 "Bryce Canyon / footprints 1579-1585 of 2223")
	)
	(layers
		(0 "F.Cu" signal "TOP")
		(4 "In1.Cu" signal "L2GND")
		(6 "In2.Cu" signal "L3")
		(8 "In3.Cu" signal "L4GND")
		(10 "In4.Cu" signal "L5")
		(12 "In5.Cu" signal "L6VCC")
		(14 "In6.Cu" signal "L7VCC")
		(16 "In7.Cu" signal "L8")
		(18 "In8.Cu" signal "L9GND")
		(20 "In9.Cu" signal "L10")
		(22 "In10.Cu" signal "L11GND")
		(2 "B.Cu" signal "BOTTOM")
		(9 "F.Adhes" user "F.Adhesive")
		(11 "B.Adhes" user "B.Adhesive")
		(13 "F.Paste" user "Package Geometry/Pastemask Top")
		(15 "B.Paste" user "Package Geometry/Pastemask Bottom")
		(5 "F.SilkS" user "Ref Des/Silkscreen Top")
		(7 "B.SilkS" user "Ref Des/Silkscreen Bottom")
		(1 "F.Mask" user "Board Geometry/Soldermask Top")
		(3 "B.Mask" user "Board Geometry/Soldermask Bottom")
		(17 "Dwgs.User" user "User.Drawings")
		(19 "Cmts.User" user "User.Comments")
		(21 "Eco1.User" user "User.Eco1")
		(23 "Eco2.User" user "User.Eco2")
		(25 "Edge.Cuts" user "Board Geometry/Outline")
		(27 "Margin" user)
		(31 "F.CrtYd" user "Package Geometry/Place Bound Top")
		(29 "B.CrtYd" user "Package Geometry/Place Bound Bottom")
		(35 "F.Fab" user "Ref Des/Assembly Top")
		(33 "B.Fab" user "Ref Des/Assembly Bottom")
	)
	(footprint ""
		(layer "F.Cu")
		(at 258.402328 16.8148 -90)
		(property "Reference" "R611"
			(at 0 0 270)
			(layer "F.SilkS")
			(hide yes)
			(effects
				(font
					(size 1.27 1.27)
				)
			)
		)
		(property "Value" "10KR2F-2-GP"
			(at 0.064008 -3.993896 270)
			(unlocked yes)
			(layer "F.Fab")
			(hide yes)
			(effects
				(font
					(size 1.016 1.016)
					(thickness 0.1524)
				)
			)
		)
		(property "Device Type" "R402H16"
			(at 0.064008 -5.517896 270)
			(unlocked yes)
			(layer "F.Fab")
			(hide yes)
			(effects
				(font
					(size 1.016 1.016)
					(thickness 0.1524)
				)
			)
		)
		(duplicate_pad_numbers_are_jumpers no)
		(fp_line
			(start -0.508 -0.9398)
			(end -0.508 0.9398)
			(stroke
				(width 0.1524)
				(type default)
			)
			(layer "F.SilkS")
		)
		(fp_line
			(start 0.508 -0.9398)
			(end -0.508 -0.9398)
			(stroke
				(width 0.1524)
				(type default)
			)
			(layer "F.SilkS")
		)
		(fp_rect
			(start -0.508 0.9398)
			(end 0.508 -0.9398)
			(stroke
				(width 0)
				(type default)
			)
			(fill no)
			(layer "F.CrtYd")
		)
		(fp_rect
			(start -0.508 0.9398)
			(end 0.508 -0.9398)
			(stroke
				(width 0)
				(type default)
			)
			(fill no)
			(layer "F.Fab")
		)
		(pad "1" smd custom
			(at 0 -0.4445 270)
			(size 0.1397 0.1397)
			(layers "F.Cu" "F.Mask" "F.Paste")
			(net "SCC_A_FAULT_LED")
			(options
				(clearance outline)
				(anchor circle)
			)
			(primitives
				(gr_poly
					(pts
						(arc
							(start -0.1778 -0.2794)
							(mid -0.249642 -0.249642)
							(end -0.2794 -0.1778)
						)
						(arc
							(start -0.2794 0.1778)
							(mid -0.249642 0.249642)
							(end -0.1778 0.2794)
						)
						(arc
							(start 0.1778 0.2794)
							(mid 0.249642 0.249642)
							(end 0.2794 0.1778)
						)
						(arc
							(start 0.2794 -0.1778)
							(mid 0.249642 -0.249642)
							(end 0.1778 -0.2794)
						)
					)
					(width 0)
					(fill yes)
				)
			)
		)
		(pad "2" smd custom
			(at 0 0.4445 270)
			(size 0.1397 0.1397)
			(layers "F.Cu" "F.Mask" "F.Paste")
			(net "GND")
			(options
				(clearance outline)
				(anchor circle)
			)
			(primitives
				(gr_poly
					(pts
						(arc
							(start -0.1778 -0.2794)
							(mid -0.249642 -0.249642)
							(end -0.2794 -0.1778)
						)
						(arc
							(start -0.2794 0.1778)
							(mid -0.249642 0.249642)
							(end -0.1778 0.2794)
						)
						(arc
							(start 0.1778 0.2794)
							(mid 0.249642 0.249642)
							(end 0.2794 0.1778)
						)
						(arc
							(start 0.2794 -0.1778)
							(mid 0.249642 -0.249642)
							(end 0.1778 -0.2794)
						)
					)
					(width 0)
					(fill yes)
				)
			)
		)
	)
	(footprint ""
		(layer "F.Cu")
		(at 235.2294 -248.9708)
		(property "Reference" "R29"
			(at 0 0 0)
			(layer "F.SilkS")
			(hide yes)
			(effects
				(font
					(size 1.27 1.27)
				)
			)
		)
		(property "Value" "0R2J-2-GP"
			(at 0.064008 -3.993896 0)
			(unlocked yes)
			(layer "F.Fab")
			(hide yes)
			(effects
				(font
					(size 1.016 1.016)
					(thickness 0.1524)
				)
			)
		)
		(property "Device Type" "R402H16"
			(at 0.064008 -5.517896 0)
			(unlocked yes)
			(layer "F.Fab")
			(hide yes)
			(effects
				(font
					(size 1.016 1.016)
					(thickness 0.1524)
				)
			)
		)
		(duplicate_pad_numbers_are_jumpers no)
		(fp_line
			(start -0.508 -0.9398)
			(end -0.508 0.9398)
			(stroke
				(width 0.1524)
				(type default)
			)
			(layer "F.SilkS")
		)
		(fp_line
			(start 0.508 -0.9398)
			(end -0.508 -0.9398)
			(stroke
				(width 0.1524)
				(type default)
			)
			(layer "F.SilkS")
		)
		(fp_rect
			(start -0.508 0.9398)
			(end 0.508 -0.9398)
			(stroke
				(width 0)
				(type default)
			)
			(fill no)
			(layer "F.CrtYd")
		)
		(fp_rect
			(start -0.508 0.9398)
			(end 0.508 -0.9398)
			(stroke
				(width 0)
				(type default)
			)
			(fill no)
			(layer "F.Fab")
		)
		(pad "1" smd custom
			(at 0 -0.4445)
			(size 0.1397 0.1397)
			(layers "F.Cu" "F.Mask" "F.Paste")
			(net "IO_EXP4_SCL")
			(options
				(clearance outline)
				(anchor circle)
			)
			(primitives
				(gr_poly
					(pts
						(arc
							(start -0.1778 -0.2794)
							(mid -0.249642 -0.249642)
							(end -0.2794 -0.1778)
						)
						(arc
							(start -0.2794 0.1778)
							(mid -0.249642 0.249642)
							(end -0.1778 0.2794)
						)
						(arc
							(start 0.1778 0.2794)
							(mid 0.249642 0.249642)
							(end 0.2794 0.1778)
						)
						(arc
							(start 0.2794 -0.1778)
							(mid 0.249642 -0.249642)
							(end 0.1778 -0.2794)
						)
					)
					(width 0)
					(fill yes)
				)
			)
		)
		(pad "2" smd custom
			(at 0 0.4445)
			(size 0.1397 0.1397)
			(layers "F.Cu" "F.Mask" "F.Paste")
			(net "I2C_DRIVE_A_INS_SCL")
			(options
				(clearance outline)
				(anchor circle)
			)
			(primitives
				(gr_poly
					(pts
						(arc
							(start -0.1778 -0.2794)
							(mid -0.249642 -0.249642)
							(end -0.2794 -0.1778)
						)
						(arc
							(start -0.2794 0.1778)
							(mid -0.249642 0.249642)
							(end -0.1778 0.2794)
						)
						(arc
							(start 0.1778 0.2794)
							(mid 0.249642 0.249642)
							(end 0.2794 0.1778)
						)
						(arc
							(start 0.2794 -0.1778)
							(mid 0.249642 -0.249642)
							(end 0.1778 -0.2794)
						)
					)
					(width 0)
					(fill yes)
				)
			)
		)
	)
	(footprint ""
		(layer "F.Cu")
		(at 47.472346 -157.839918 90)
		(property "Reference" "R444"
			(at 0 0 90)
			(layer "F.SilkS")
			(hide yes)
			(effects
				(font
					(size 1.27 1.27)
				)
			)
		)
		(property "Value" "4K7R2J-2-GP"
			(at 0.064008 -3.993896 90)
			(unlocked yes)
			(layer "F.Fab")
			(hide yes)
			(effects
				(font
					(size 1.016 1.016)
					(thickness 0.1524)
				)
			)
		)
		(property "Device Type" "R402H16"
			(at 0.064008 -5.517896 90)
			(unlocked yes)
			(layer "F.Fab")
			(hide yes)
			(effects
				(font
					(size 1.016 1.016)
					(thickness 0.1524)
				)
			)
		)
		(duplicate_pad_numbers_are_jumpers no)
		(fp_line
			(start 0.508 -0.9398)
			(end -0.508 -0.9398)
			(stroke
				(width 0.1524)
				(type default)
			)
			(layer "F.SilkS")
		)
		(fp_line
			(start -0.508 -0.9398)
			(end -0.508 0.9398)
			(stroke
				(width 0.1524)
				(type default)
			)
			(layer "F.SilkS")
		)
		(fp_rect
			(start -0.508 0.9398)
			(end 0.508 -0.9398)
			(stroke
				(width 0)
				(type default)
			)
			(fill no)
			(layer "F.CrtYd")
		)
		(fp_rect
			(start -0.508 0.9398)
			(end 0.508 -0.9398)
			(stroke
				(width 0)
				(type default)
			)
			(fill no)
			(layer "F.Fab")
		)
		(pad "1" smd custom
			(at 0 -0.4445 90)
			(size 0.1397 0.1397)
			(layers "F.Cu" "F.Mask" "F.Paste")
			(net "P12V_A")
			(options
				(clearance outline)
				(anchor circle)
			)
			(primitives
				(gr_poly
					(pts
						(arc
							(start -0.1778 -0.2794)
							(mid -0.249642 -0.249642)
							(end -0.2794 -0.1778)
						)
						(arc
							(start -0.2794 0.1778)
							(mid -0.249642 0.249642)
							(end -0.1778 0.2794)
						)
						(arc
							(start 0.1778 0.2794)
							(mid 0.249642 0.249642)
							(end 0.2794 0.1778)
						)
						(arc
							(start 0.2794 -0.1778)
							(mid 0.249642 -0.249642)
							(end 0.1778 -0.2794)
						)
					)
					(width 0)
					(fill yes)
				)
			)
		)
		(pad "2" smd custom
			(at 0 0.4445 90)
			(size 0.1397 0.1397)
			(layers "F.Cu" "F.Mask" "F.Paste")
			(net "SW_HDD_R13")
			(options
				(clearance outline)
				(anchor circle)
			)
			(primitives
				(gr_poly
					(pts
						(arc
							(start -0.1778 -0.2794)
							(mid -0.249642 -0.249642)
							(end -0.2794 -0.1778)
						)
						(arc
							(start -0.2794 0.1778)
							(mid -0.249642 0.249642)
							(end -0.1778 0.2794)
						)
						(arc
							(start 0.1778 0.2794)
							(mid 0.249642 0.249642)
							(end 0.2794 0.1778)
						)
						(arc
							(start 0.2794 -0.1778)
							(mid 0.249642 -0.249642)
							(end 0.1778 -0.2794)
						)
					)
					(width 0)
					(fill yes)
				)
			)
		)
	)
	(footprint ""
		(layer "F.Cu")
		(at 254.811276 -261.32536 180)
		(property "Reference" "R57"
			(at 0 0 180)
			(layer "F.SilkS")
			(hide yes)
			(effects
				(font
					(size 1.27 1.27)
				)
			)
		)
		(property "Value" "0R2J-2-GP"
			(at 0.064008 -3.993896 180)
			(unlocked yes)
			(layer "F.Fab")
			(hide yes)
			(effects
				(font
					(size 1.016 1.016)
					(thickness 0.1524)
				)
			)
		)
		(property "Device Type" "R402H16"
			(at 0.064008 -5.517896 180)
			(unlocked yes)
			(layer "F.Fab")
			(hide yes)
			(effects
				(font
					(size 1.016 1.016)
					(thickness 0.1524)
				)
			)
		)
		(duplicate_pad_numbers_are_jumpers no)
		(fp_line
			(start 0.508 -0.9398)
			(end -0.508 -0.9398)
			(stroke
				(width 0.1524)
				(type default)
			)
			(layer "F.SilkS")
		)
		(fp_line
			(start -0.508 -0.9398)
			(end -0.508 0.9398)
			(stroke
				(width 0.1524)
				(type default)
			)
			(layer "F.SilkS")
		)
		(fp_rect
			(start -0.508 0.9398)
			(end 0.508 -0.9398)
			(stroke
				(width 0)
				(type default)
			)
			(fill no)
			(layer "F.CrtYd")
		)
		(fp_rect
			(start -0.508 0.9398)
			(end 0.508 -0.9398)
			(stroke
				(width 0)
				(type default)
			)
			(fill no)
			(layer "F.Fab")
		)
		(pad "1" smd custom
			(at 0 -0.4445 180)
			(size 0.1397 0.1397)
			(layers "F.Cu" "F.Mask" "F.Paste")
			(net "IO_EXP6_SCL")
			(options
				(clearance outline)
				(anchor circle)
			)
			(primitives
				(gr_poly
					(pts
						(arc
							(start -0.1778 -0.2794)
							(mid -0.249642 -0.249642)
							(end -0.2794 -0.1778)
						)
						(arc
							(start -0.2794 0.1778)
							(mid -0.249642 0.249642)
							(end -0.1778 0.2794)
						)
						(arc
							(start 0.1778 0.2794)
							(mid 0.249642 0.249642)
							(end 0.2794 0.1778)
						)
						(arc
							(start 0.2794 -0.1778)
							(mid 0.249642 -0.249642)
							(end 0.1778 -0.2794)
						)
					)
					(width 0)
					(fill yes)
				)
			)
		)
		(pad "2" smd custom
			(at 0 0.4445 180)
			(size 0.1397 0.1397)
			(layers "F.Cu" "F.Mask" "F.Paste")
			(net "I2C_DRIVE_A_INS_SCL")
			(options
				(clearance outline)
				(anchor circle)
			)
			(primitives
				(gr_poly
					(pts
						(arc
							(start -0.1778 -0.2794)
							(mid -0.249642 -0.249642)
							(end -0.2794 -0.1778)
						)
						(arc
							(start -0.2794 0.1778)
							(mid -0.249642 0.249642)
							(end -0.1778 0.2794)
						)
						(arc
							(start 0.1778 0.2794)
							(mid 0.249642 0.249642)
							(end 0.2794 0.1778)
						)
						(arc
							(start 0.2794 -0.1778)
							(mid 0.249642 -0.249642)
							(end 0.1778 -0.2794)
						)
					)
					(width 0)
					(fill yes)
				)
			)
		)
	)
	(footprint ""
		(layer "F.Cu")
		(at 141.042898 -54.523894 90)
		(property "Reference" "C413"
			(at 0 0 90)
			(layer "F.SilkS")
			(hide yes)
			(effects
				(font
					(size 1.27 1.27)
				)
			)
		)
		(property "Value" "SCD033U25V2KX-GP"
			(at 1.1811 -2.7051 90)
			(unlocked yes)
			(layer "F.Fab")
			(hide yes)
			(effects
				(font
					(size 1.016 1.016)
					(thickness 0.1524)
				)
			)
		)
		(property "Device Type" "C402H22"
			(at 1.1811 -4.2291 90)
			(unlocked yes)
			(layer "F.Fab")
			(hide yes)
			(effects
				(font
					(size 1.016 1.016)
					(thickness 0.1524)
				)
			)
		)
		(duplicate_pad_numbers_are_jumpers no)
		(fp_rect
			(start -0.4318 0.9525)
			(end 0.4318 -0.9525)
			(stroke
				(width 0)
				(type default)
			)
			(fill no)
			(layer "F.CrtYd")
		)
		(fp_rect
			(start -0.4318 0.9525)
			(end 0.4318 -0.9525)
			(stroke
				(width 0)
				(type default)
			)
			(fill no)
			(layer "F.Fab")
		)
		(pad "1" smd custom
			(at 0 -0.4445 90)
			(size 0.1524 0.1524)
			(layers "F.Cu" "F.Mask" "F.Paste")
			(net "P12V_A")
			(options
				(clearance outline)
				(anchor circle)
			)
			(primitives
				(gr_poly
					(pts
						(arc
							(start 0.3048 -0.2032)
							(mid 0.275042 -0.275042)
							(end 0.2032 -0.3048)
						)
						(arc
							(start -0.2032 -0.3048)
							(mid -0.275042 -0.275042)
							(end -0.3048 -0.2032)
						)
						(arc
							(start -0.3048 0.2032)
							(mid -0.275042 0.275042)
							(end -0.2032 0.3048)
						)
						(arc
							(start 0.2032 0.3048)
							(mid 0.275042 0.275042)
							(end 0.3048 0.2032)
						)
					)
					(width 0)
					(fill yes)
				)
			)
		)
		(pad "2" smd custom
			(at 0 0.4445 90)
			(size 0.1524 0.1524)
			(layers "F.Cu" "F.Mask" "F.Paste")
			(net "SW_HDD_N28")
			(options
				(clearance outline)
				(anchor circle)
			)
			(primitives
				(gr_poly
					(pts
						(arc
							(start 0.3048 -0.2032)
							(mid 0.275042 -0.275042)
							(end 0.2032 -0.3048)
						)
						(arc
							(start -0.2032 -0.3048)
							(mid -0.275042 -0.275042)
							(end -0.3048 -0.2032)
						)
						(arc
							(start -0.3048 0.2032)
							(mid -0.275042 0.275042)
							(end -0.2032 0.3048)
						)
						(arc
							(start 0.2032 0.3048)
							(mid 0.275042 0.275042)
							(end 0.3048 0.2032)
						)
					)
					(width 0)
					(fill yes)
				)
			)
		)
	)
	(footprint ""
		(layer "F.Cu")
		(at 180.7464 -44.821094 -90)
		(property "Reference" "R808"
			(at 0 0 270)
			(layer "F.SilkS")
			(hide yes)
			(effects
				(font
					(size 1.27 1.27)
				)
			)
		)
		(property "Value" "0R2J-2-GP"
			(at 0.064008 -3.993896 270)
			(unlocked yes)
			(layer "F.Fab")
			(hide yes)
			(effects
				(font
					(size 1.016 1.016)
					(thickness 0.1524)
				)
			)
		)
		(property "Device Type" "R402H16"
			(at 0.064008 -5.517896 270)
			(unlocked yes)
			(layer "F.Fab")
			(hide yes)
			(effects
				(font
					(size 1.016 1.016)
					(thickness 0.1524)
				)
			)
		)
		(duplicate_pad_numbers_are_jumpers no)
		(fp_line
			(start -0.508 -0.9398)
			(end -0.508 0.9398)
			(stroke
				(width 0.1524)
				(type default)
			)
			(layer "F.SilkS")
		)
		(fp_line
			(start 0.508 -0.9398)
			(end -0.508 -0.9398)
			(stroke
				(width 0.1524)
				(type default)
			)
			(layer "F.SilkS")
		)
		(fp_rect
			(start -0.508 0.9398)
			(end 0.508 -0.9398)
			(stroke
				(width 0)
				(type default)
			)
			(fill no)
			(layer "F.CrtYd")
		)
		(fp_rect
			(start -0.508 0.9398)
			(end 0.508 -0.9398)
			(stroke
				(width 0)
				(type default)
			)
			(fill no)
			(layer "F.Fab")
		)
		(pad "1" smd custom
			(at 0 -0.4445 270)
			(size 0.1397 0.1397)
			(layers "F.Cu" "F.Mask" "F.Paste")
			(net "DRIVE_A_29_PWR")
			(options
				(clearance outline)
				(anchor circle)
			)
			(primitives
				(gr_poly
					(pts
						(arc
							(start -0.1778 -0.2794)
							(mid -0.249642 -0.249642)
							(end -0.2794 -0.1778)
						)
						(arc
							(start -0.2794 0.1778)
							(mid -0.249642 0.249642)
							(end -0.1778 0.2794)
						)
						(arc
							(start 0.1778 0.2794)
							(mid 0.249642 0.249642)
							(end 0.2794 0.1778)
						)
						(arc
							(start 0.2794 -0.1778)
							(mid 0.249642 -0.249642)
							(end 0.1778 -0.2794)
						)
					)
					(width 0)
					(fill yes)
				)
			)
		)
		(pad "2" smd custom
			(at 0 0.4445 270)
			(size 0.1397 0.1397)
			(layers "F.Cu" "F.Mask" "F.Paste")
			(net "SW_PWR_R_HDD29")
			(options
				(clearance outline)
				(anchor circle)
			)
			(primitives
				(gr_poly
					(pts
						(arc
							(start -0.1778 -0.2794)
							(mid -0.249642 -0.249642)
							(end -0.2794 -0.1778)
						)
						(arc
							(start -0.2794 0.1778)
							(mid -0.249642 0.249642)
							(end -0.1778 0.2794)
						)
						(arc
							(start 0.1778 0.2794)
							(mid 0.249642 0.249642)
							(end 0.2794 0.1778)
						)
						(arc
							(start 0.2794 -0.1778)
							(mid 0.249642 -0.249642)
							(end 0.1778 -0.2794)
						)
					)
					(width 0)
					(fill yes)
				)
			)
		)
	)
	(footprint ""
		(layer "F.Cu")
		(at 245.499128 -390.723628 -90)
		(property "Reference" "R1141"
			(at 0 0 270)
			(layer "F.SilkS")
			(hide yes)
			(effects
				(font
					(size 1.27 1.27)
				)
			)
		)
		(property "Value" "10R2F-L-GP"
			(at 0.064008 -3.993896 270)
			(unlocked yes)
			(layer "F.Fab")
			(hide yes)
			(effects
				(font
					(size 1.016 1.016)
					(thickness 0.1524)
				)
			)
		)
		(property "Device Type" "R402H14"
			(at 0.064008 -5.517896 270)
			(unlocked yes)
			(layer "F.Fab")
			(hide yes)
			(effects
				(font
					(size 1.016 1.016)
					(thickness 0.1524)
				)
			)
		)
		(duplicate_pad_numbers_are_jumpers no)
		(fp_line
			(start -0.508 -0.9398)
			(end -0.508 0.9398)
			(stroke
				(width 0.1524)
				(type default)
			)
			(layer "F.SilkS")
		)
		(fp_line
			(start 0.508 -0.9398)
			(end -0.508 -0.9398)
			(stroke
				(width 0.1524)
				(type default)
			)
			(layer "F.SilkS")
		)
		(fp_rect
			(start -0.508 0.9398)
			(end 0.508 -0.9398)
			(stroke
				(width 0)
				(type default)
			)
			(fill no)
			(layer "F.CrtYd")
		)
		(fp_rect
			(start -0.508 0.9398)
			(end 0.508 -0.9398)
			(stroke
				(width 0)
				(type default)
			)
			(fill no)
			(layer "F.Fab")
		)
		(pad "1" smd custom
			(at 0 -0.4445 270)
			(size 0.1397 0.1397)
			(layers "F.Cu" "F.Mask" "F.Paste")
			(net "P12V_IN")
			(options
				(clearance outline)
				(anchor circle)
			)
			(primitives
				(gr_poly
					(pts
						(arc
							(start -0.1778 -0.2794)
							(mid -0.249642 -0.249642)
							(end -0.2794 -0.1778)
						)
						(arc
							(start -0.2794 0.1778)
							(mid -0.249642 0.249642)
							(end -0.1778 0.2794)
						)
						(arc
							(start 0.1778 0.2794)
							(mid 0.249642 0.249642)
							(end 0.2794 0.1778)
						)
						(arc
							(start 0.2794 -0.1778)
							(mid 0.249642 -0.249642)
							(end 0.1778 -0.2794)
						)
					)
					(width 0)
					(fill yes)
				)
			)
		)
		(pad "2" smd custom
			(at 0 0.4445 270)
			(size 0.1397 0.1397)
			(layers "F.Cu" "F.Mask" "F.Paste")
			(net "MB3_P12V_HS")
			(options
				(clearance outline)
				(anchor circle)
			)
			(primitives
				(gr_poly
					(pts
						(arc
							(start -0.1778 -0.2794)
							(mid -0.249642 -0.249642)
							(end -0.2794 -0.1778)
						)
						(arc
							(start -0.2794 0.1778)
							(mid -0.249642 0.249642)
							(end -0.1778 0.2794)
						)
						(arc
							(start 0.1778 0.2794)
							(mid 0.249642 0.249642)
							(end 0.2794 0.1778)
						)
						(arc
							(start 0.2794 -0.1778)
							(mid 0.249642 -0.249642)
							(end 0.1778 -0.2794)
						)
					)
					(width 0)
					(fill yes)
				)
			)
		)
	)
)
